# TIMECARD (Time Appliance Project (Time Card)) — schematic netlist excerpt (pin names and nets, part order shuffled) for the footprints in the layout excerpt that follows; sources: Cadence DE-HDL packaged netlist, KiCad conversion of R4006-B0001-02_R01.brd

GF1  CONN_64P_GF  pkg S_M_EF64_PCIE_P0394_V1  page 9
  \prsnt1*\  = CARD_PRESENT
  P_12V3  = XP12R0V_PCIE
  P_12V5  = XP12R0V_PCIE
  GND2  = SG
  JTAG2  = PCIE_CONN_TCK
  JTAG3  = PCIE_CONN_TDI
  JTAG4  = PCIE_CONN_TDO
  JTAG5  = PCIE_CONN_TMS
  P_3V3_2  = XP3R3V_PCIE
  P_3V3_3  = XP3R3V_PCIE
  \perst*\  = PCIE_CONN_PERST_N
  GND4  = SG
  REFCLK_P  = C_PCIEREFCLKP
  REFCLK_N  = C_PCIEREFCLKN
  GND6  = SG
  PERP0  = C_CPU_RX_PCIE_MGT0_TXP
  PERN0  = C_CPU_RX_PCIE_MGT0_TXN
  GND8  = SG
  RSVD2  = NC
  GND10  = SG
  PERP1  = C_CPU_RX_PCIE_MGT1_TXP
  PERN1  = C_CPU_RX_PCIE_MGT1_TXN
  GND13  = SG
  GND14  = SG
  PERP2  = C_CPU_RX_PCIE_MGT2_TXP
  PERN2  = C_CPU_RX_PCIE_MGT2_TXN
  GND18  = SG
  GND19  = SG
  PERP3  = C_CPU_RX_PCIE_MGT3_TXP
  PERN3  = C_CPU_RX_PCIE_MGT3_TXN
  GND21  = SG
  RSVD4  = NC
  P_12V1  = XP12R0V_PCIE
  P_12V2  = XP12R0V_PCIE
  P_12V4  = XP12R0V_PCIE
  GND1  = SG
  SMCLK  = PCIE_CONN_SMCLK
  SMDAT  = PCIE_CONN_SMDAT
  GND3  = SG
  P_3V3_1  = XP3R3V_PCIE
  JTAG1  = NC
  P_3V3AUX  = XP3R3V_AUX_PCIE
  \wake*\  = NC
  RSVD1  = NC
  GND5  = SG
  PETP0  = CPU_TX_PCIE_MGT_0_RXP
  PETN0  = CPU_TX_PCIE_MGT_0_RXN
  GND7  = SG
  \prsnt2_1*\  = UNNAMED_3_CONN64PGF_I61_PRSNT21
  GND9  = SG
  PETP1  = CPU_TX_PCIE_MGT_1_RXP
  PETN1  = CPU_TX_PCIE_MGT_1_RXN
  GND11  = SG
  GND12  = SG
  PETP2  = CPU_TX_PCIE_MGT_2_RXP
  PETN2  = CPU_TX_PCIE_MGT_2_RXN
  GND15  = SG
  GND17  = SG
  PETP3  = CPU_TX_PCIE_MGT_3_RXP
  PETN3  = CPU_TX_PCIE_MGT_3_RXN
  GND20  = SG
  RSVD3  = NC
  \prsnt2_2*\  = UNNAMED_3_CONN64PGF_I61_PRSNT22
  GND22  = SG

(kicad_pcb
	(version 20260206)
	(generator "pcbnew")
	(generator_version "10.0")
	(general
		(thickness 1.6)
		(legacy_teardrops no)
	)
	(paper "A4")
	(title_block
		(title "timecard-production-celestica-r4006 — R4006-B0001-02_R01.brd")
		(comment 1 "Time Appliance Project (Time Card) / footprint 606 of 1113 (GF1), pads 49-64 of 64")
	)
	(layers
		(0 "F.Cu" signal "TOP")
		(4 "In1.Cu" signal "L02_GND1")
		(6 "In2.Cu" signal "L03_SIG1")
		(8 "In3.Cu" signal "L04_GND2")
		(10 "In4.Cu" signal "L05_VCC1")
		(12 "In5.Cu" signal "L06_VCC2")
		(14 "In6.Cu" signal "L07_GND3")
		(16 "In7.Cu" signal "L08_SIG2")
		(18 "In8.Cu" signal "L09_GND4")
		(2 "B.Cu" signal "BOTTOM")
		(9 "F.Adhes" user "F.Adhesive")
		(11 "B.Adhes" user "B.Adhesive")
		(13 "F.Paste" user "Package Geometry/Pastemask Top")
		(15 "B.Paste" user "Package Geometry/Pastemask Bottom")
		(5 "F.SilkS" user "Ref Des/Silkscreen Top")
		(7 "B.SilkS" user "Ref Des/Silkscreen Bottom")
		(1 "F.Mask" user "Board Geometry/Soldermask Top")
		(3 "B.Mask" user "Board Geometry/Soldermask Bottom")
		(17 "Dwgs.User" user "User.Drawings")
		(19 "Cmts.User" user "User.Comments")
		(21 "Eco1.User" user "User.Eco1")
		(23 "Eco2.User" user "User.Eco2")
		(25 "Edge.Cuts" user "Board Geometry/Outline")
		(27 "Margin" user)
		(31 "F.CrtYd" user "Package Geometry/Place Bound Top")
		(29 "B.CrtYd" user "Package Geometry/Place Bound Bottom")
		(35 "F.Fab" user "Ref Des/Assembly Top")
		(33 "B.Fab" user "Ref Des/Assembly Bottom")
	)
	(footprint ""
		(layer "F.Cu")
		(at 45.649896 -3.500374)
		(property "Reference" "GF1"
			(at 13.786104 -5.350256 0)
			(unlocked yes)
			(layer "F.SilkS")
			(effects
				(font
					(size 0.7874 0.5842)
					(thickness 0.1524)
				)
			)
		)
		(property "Value" ""
			(at 0 0 0)
			(layer "F.Fab")
			(effects
				(font
					(size 1.27 1.27)
				)
			)
		)
		(property "Device Type" "CONN_64P_GF-S_M_EF64_PCIE_P039A"
			(at 19.1262 4.810506 0)
			(unlocked yes)
			(layer "F.Fab")
			(hide yes)
			(effects
				(font
					(size 0.7874 0.5842)
					(thickness 0.1524)
				)
			)
		)
		(property "User Part Number" "PARTNUM*"
			(at 19.1262 5.978906 0)
			(unlocked yes)
			(layer "Cmts.User")
			(hide yes)
			(effects
				(font
					(size 0.7874 0.5842)
					(thickness 0.1524)
				)
			)
		)
		(duplicate_pad_numbers_are_jumpers no)
		(pad "B17" smd rect
			(at 17.999964 0)
			(size 0.7112 4.191)
			(layers "F.Cu" "F.Mask" "F.Paste")
			(net "UNNAMED_3_CONN64PGF_I61_PRSNT21")
		)
		(pad "B18" smd rect
			(at 18.999962 0)
			(size 0.7112 4.191)
			(layers "F.Cu" "F.Mask" "F.Paste")
			(net "SG")
		)
		(pad "B19" smd rect
			(at 19.99996 0)
			(size 0.7112 4.191)
			(layers "F.Cu" "F.Mask" "F.Paste")
			(net "CPU_TX_PCIE_MGT_1_RXP")
		)
		(pad "B20" smd rect
			(at 20.999958 0)
			(size 0.7112 4.191)
			(layers "F.Cu" "F.Mask" "F.Paste")
			(net "CPU_TX_PCIE_MGT_1_RXN")
		)
		(pad "B21" smd rect
			(at 21.999956 0)
			(size 0.7112 4.191)
			(layers "F.Cu" "F.Mask" "F.Paste")
			(net "SG")
		)
		(pad "B22" smd rect
			(at 22.999954 0)
			(size 0.7112 4.191)
			(layers "F.Cu" "F.Mask" "F.Paste")
			(net "SG")
		)
		(pad "B23" smd rect
			(at 23.999952 0)
			(size 0.7112 4.191)
			(layers "F.Cu" "F.Mask" "F.Paste")
			(net "CPU_TX_PCIE_MGT_2_RXP")
		)
		(pad "B24" smd rect
			(at 24.99995 0)
			(size 0.7112 4.191)
			(layers "F.Cu" "F.Mask" "F.Paste")
			(net "CPU_TX_PCIE_MGT_2_RXN")
		)
		(pad "B25" smd rect
			(at 25.999948 0)
			(size 0.7112 4.191)
			(layers "F.Cu" "F.Mask" "F.Paste")
			(net "SG")
		)
		(pad "B26" smd rect
			(at 26.999946 0)
			(size 0.7112 4.191)
			(layers "F.Cu" "F.Mask" "F.Paste")
			(net "SG")
		)
		(pad "B27" smd rect
			(at 27.999944 0)
			(size 0.7112 4.191)
			(layers "F.Cu" "F.Mask" "F.Paste")
			(net "CPU_TX_PCIE_MGT_3_RXP")
		)
		(pad "B28" smd rect
			(at 28.999942 0)
			(size 0.7112 4.191)
			(layers "F.Cu" "F.Mask" "F.Paste")
			(net "CPU_TX_PCIE_MGT_3_RXN")
		)
		(pad "B29" smd rect
			(at 29.99994 0)
			(size 0.7112 4.191)
			(layers "F.Cu" "F.Mask" "F.Paste")
			(net "SG")
		)
		(pad "B30" smd rect
			(at 30.999938 0)
			(size 0.7112 4.191)
			(layers "F.Cu" "F.Mask" "F.Paste")
			(net "Net_751")
		)
		(pad "B31" smd rect
			(at 31.999936 -0.4953)
			(size 0.7112 3.2004)
			(layers "F.Cu" "F.Mask" "F.Paste")
			(net "UNNAMED_3_CONN64PGF_I61_PRSNT22")
		)
		(pad "B32" smd rect
			(at 32.999934 0)
			(size 0.7112 4.191)
			(layers "F.Cu" "F.Mask" "F.Paste")
			(net "SG")
		)
	)
)
